(kicad_pcb
	(version 20260206)
	(generator "pcbnew")
	(generator_version "10.0")
	(general
		(thickness 1.6)
		(legacy_teardrops no)
	)
	(paper "A4")
	(title_block
		(title "Bryce Canyon_IOM_IOC_16318-2_OCP.brd")
		(comment 1 "Bryce Canyon / footprints 747-754 of 1605")
	)
	(layers
		(0 "F.Cu" signal "TOP")
		(4 "In1.Cu" signal "L2GND")
		(6 "In2.Cu" signal "L3")
		(8 "In3.Cu" signal "L4VCC")
		(10 "In4.Cu" signal "L5VCC")
		(12 "In5.Cu" signal "L6")
		(14 "In6.Cu" signal "L7GND")
		(2 "B.Cu" signal "BOTTOM")
		(9 "F.Adhes" user "F.Adhesive")
		(11 "B.Adhes" user "B.Adhesive")
		(13 "F.Paste" user "Package Geometry/Pastemask Top")
		(15 "B.Paste" user "Package Geometry/Pastemask Bottom")
		(5 "F.SilkS" user "Ref Des/Silkscreen Top")
		(7 "B.SilkS" user "Ref Des/Silkscreen Bottom")
		(1 "F.Mask" user "Board Geometry/Soldermask Top")
		(3 "B.Mask" user "Board Geometry/Soldermask Bottom")
		(17 "Dwgs.User" user "User.Drawings")
		(19 "Cmts.User" user "User.Comments")
		(21 "Eco1.User" user "User.Eco1")
		(23 "Eco2.User" user "User.Eco2")
		(25 "Edge.Cuts" user "Board Geometry/Outline")
		(27 "Margin" user)
		(31 "F.CrtYd" user "Package Geometry/Place Bound Top")
		(29 "B.CrtYd" user "Package Geometry/Place Bound Bottom")
		(35 "F.Fab" user "Ref Des/Assembly Top")
		(33 "B.Fab" user "Ref Des/Assembly Bottom")
	)
	(footprint ""
		(layer "F.Cu")
		(at 39.1922 -179.12461)
		(property "Reference" "R491"
			(at 0 0 0)
			(layer "F.SilkS")
			(hide yes)
			(effects
				(font
					(size 1.27 1.27)
				)
			)
		)
		(property "Value" "15KR2F-GP"
			(at 0.064008 -3.993896 0)
			(unlocked yes)
			(layer "F.Fab")
			(hide yes)
			(effects
				(font
					(size 1.016 1.016)
					(thickness 0.1524)
				)
			)
		)
		(property "Device Type" "R402H16"
			(at 0.064008 -5.517896 0)
			(unlocked yes)
			(layer "F.Fab")
			(hide yes)
			(effects
				(font
					(size 1.016 1.016)
					(thickness 0.1524)
				)
			)
		)
		(duplicate_pad_numbers_are_jumpers no)
		(fp_line
			(start -0.508 -0.9398)
			(end -0.508 0.9398)
			(stroke
				(width 0.1524)
				(type default)
			)
			(layer "F.SilkS")
		)
		(fp_line
			(start 0.508 -0.9398)
			(end -0.508 -0.9398)
			(stroke
				(width 0.1524)
				(type default)
			)
			(layer "F.SilkS")
		)
		(fp_rect
			(start -0.508 0.9398)
			(end 0.508 -0.9398)
			(stroke
				(width 0)
				(type default)
			)
			(fill no)
			(layer "F.CrtYd")
		)
		(fp_rect
			(start -0.508 0.9398)
			(end 0.508 -0.9398)
			(stroke
				(width 0)
				(type default)
			)
			(fill no)
			(layer "F.Fab")
		)
		(pad "1" smd custom
			(at 0 -0.4445)
			(size 0.1397 0.1397)
			(layers "F.Cu" "F.Mask" "F.Paste")
			(net "PWRGD_P3V3_STBY")
			(options
				(clearance outline)
				(anchor circle)
			)
			(primitives
				(gr_poly
					(pts
						(arc
							(start -0.1778 -0.2794)
							(mid -0.249642 -0.249642)
							(end -0.2794 -0.1778)
						)
						(arc
							(start -0.2794 0.1778)
							(mid -0.249642 0.249642)
							(end -0.1778 0.2794)
						)
						(arc
							(start 0.1778 0.2794)
							(mid 0.249642 0.249642)
							(end 0.2794 0.1778)
						)
						(arc
							(start 0.2794 -0.1778)
							(mid 0.249642 -0.249642)
							(end 0.1778 -0.2794)
						)
					)
					(width 0)
					(fill yes)
				)
			)
		)
		(pad "2" smd custom
			(at 0 0.4445)
			(size 0.1397 0.1397)
			(layers "F.Cu" "F.Mask" "F.Paste")
			(net "GND")
			(options
				(clearance outline)
				(anchor circle)
			)
			(primitives
				(gr_poly
					(pts
						(arc
							(start -0.1778 -0.2794)
							(mid -0.249642 -0.249642)
							(end -0.2794 -0.1778)
						)
						(arc
							(start -0.2794 0.1778)
							(mid -0.249642 0.249642)
							(end -0.1778 0.2794)
						)
						(arc
							(start 0.1778 0.2794)
							(mid 0.249642 0.249642)
							(end 0.2794 0.1778)
						)
						(arc
							(start 0.2794 -0.1778)
							(mid 0.249642 -0.249642)
							(end 0.1778 -0.2794)
						)
					)
					(width 0)
					(fill yes)
				)
			)
		)
	)
	(footprint ""
		(layer "F.Cu")
		(at 60.375546 -185.000138 -90)
		(property "Reference" "R480"
			(at 0 0 270)
			(layer "F.SilkS")
			(hide yes)
			(effects
				(font
					(size 1.27 1.27)
				)
			)
		)
		(property "Value" "0R6J-3-GP"
			(at -0.0508 -4.8514 270)
			(unlocked yes)
			(layer "F.Fab")
			(hide yes)
			(effects
				(font
					(size 1.016 1.016)
					(thickness 0.1524)
				)
			)
		)
		(property "Device Type" "R1206H28"
			(at 0 -6.3754 270)
			(unlocked yes)
			(layer "F.Fab")
			(hide yes)
			(effects
				(font
					(size 1.016 1.016)
					(thickness 0.1524)
				)
			)
		)
		(duplicate_pad_numbers_are_jumpers no)
		(fp_line
			(start -1.016 2.2352)
			(end -1.016 -2.2352)
			(stroke
				(width 0.1524)
				(type default)
			)
			(layer "F.SilkS")
		)
		(fp_line
			(start 1.016 2.2352)
			(end -1.016 2.2352)
			(stroke
				(width 0.1524)
				(type default)
			)
			(layer "F.SilkS")
		)
		(fp_line
			(start -1.016 -2.2352)
			(end 1.016 -2.2352)
			(stroke
				(width 0.1524)
				(type default)
			)
			(layer "F.SilkS")
		)
		(fp_line
			(start 1.016 -2.2352)
			(end 1.016 2.2352)
			(stroke
				(width 0.1524)
				(type default)
			)
			(layer "F.SilkS")
		)
		(fp_rect
			(start -1.0922 2.3114)
			(end 1.0922 -2.3114)
			(stroke
				(width 0)
				(type default)
			)
			(fill no)
			(layer "F.CrtYd")
		)
		(fp_poly
			(pts
				(xy -1.0922 -2.3114) (xy 1.0922 -2.3114) (xy 1.0922 2.3114) (xy -1.0922 2.3114)
			)
			(stroke
				(width 0)
				(type default)
			)
			(fill no)
			(layer "F.Fab")
		)
		(pad "1" smd rect
			(at 0 -1.397 270)
			(size 1.651 1.27)
			(layers "F.Cu" "F.Mask" "F.Paste")
			(net "P3V3_STBY")
		)
		(pad "2" smd rect
			(at 0 1.397 270)
			(size 1.651 1.27)
			(layers "F.Cu" "F.Mask" "F.Paste")
			(net "P3V3_STBY_OUT")
		)
	)
	(footprint ""
		(layer "F.Cu")
		(at 94.488 -29.464 90)
		(property "Reference" "C21"
			(at 0 0 90)
			(layer "F.SilkS")
			(hide yes)
			(effects
				(font
					(size 1.27 1.27)
				)
			)
		)
		(property "Value" "SC1U16V3KX-5GP"
			(at 0 -2.8194 90)
			(unlocked yes)
			(layer "F.Fab")
			(hide yes)
			(effects
				(font
					(size 1.016 1.016)
					(thickness 0.1524)
				)
			)
		)
		(property "Device Type" "C603H36"
			(at 0 -4.3434 90)
			(unlocked yes)
			(layer "F.Fab")
			(hide yes)
			(effects
				(font
					(size 1.016 1.016)
					(thickness 0.1524)
				)
			)
		)
		(duplicate_pad_numbers_are_jumpers no)
		(fp_line
			(start 0.508 0)
			(end -0.508 0)
			(stroke
				(width 0.2032)
				(type default)
			)
			(layer "F.SilkS")
		)
		(fp_rect
			(start -0.5842 1.3335)
			(end 0.5842 -1.3335)
			(stroke
				(width 0)
				(type default)
			)
			(fill no)
			(layer "F.CrtYd")
		)
		(fp_rect
			(start -0.5842 1.3335)
			(end 0.5842 -1.3335)
			(stroke
				(width 0)
				(type default)
			)
			(fill no)
			(layer "F.Fab")
		)
		(pad "1" smd custom
			(at 0 -0.762 90)
			(size 0.2159 0.2159)
			(layers "F.Cu" "F.Mask" "F.Paste")
			(net "P5V_USB")
			(options
				(clearance outline)
				(anchor circle)
			)
			(primitives
				(gr_poly
					(pts
						(arc
							(start -0.3302 -0.4318)
							(mid -0.402042 -0.402042)
							(end -0.4318 -0.3302)
						)
						(arc
							(start -0.4318 0.3302)
							(mid -0.402042 0.402042)
							(end -0.3302 0.4318)
						)
						(arc
							(start 0.3302 0.4318)
							(mid 0.402042 0.402042)
							(end 0.4318 0.3302)
						)
						(arc
							(start 0.4318 -0.3302)
							(mid 0.402042 -0.402042)
							(end 0.3302 -0.4318)
						)
					)
					(width 0)
					(fill yes)
				)
			)
		)
		(pad "2" smd custom
			(at 0 0.762 90)
			(size 0.2159 0.2159)
			(layers "F.Cu" "F.Mask" "F.Paste")
			(net "GND")
			(options
				(clearance outline)
				(anchor circle)
			)
			(primitives
				(gr_poly
					(pts
						(arc
							(start -0.3302 -0.4318)
							(mid -0.402042 -0.402042)
							(end -0.4318 -0.3302)
						)
						(arc
							(start -0.4318 0.3302)
							(mid -0.402042 0.402042)
							(end -0.3302 0.4318)
						)
						(arc
							(start 0.3302 0.4318)
							(mid 0.402042 0.402042)
							(end 0.4318 0.3302)
						)
						(arc
							(start 0.4318 -0.3302)
							(mid 0.402042 -0.402042)
							(end 0.3302 -0.4318)
						)
					)
					(width 0)
					(fill yes)
				)
			)
		)
	)
	(footprint ""
		(layer "F.Cu")
		(at 31.5976 -160.6042 90)
		(property "Reference" "R706"
			(at 0 0 90)
			(layer "F.SilkS")
			(hide yes)
			(effects
				(font
					(size 1.27 1.27)
				)
			)
		)
		(property "Value" "4K7R2F-GP"
			(at 0.064008 -3.993896 90)
			(unlocked yes)
			(layer "F.Fab")
			(hide yes)
			(effects
				(font
					(size 1.016 1.016)
					(thickness 0.1524)
				)
			)
		)
		(property "Device Type" "R402H16"
			(at 0.064008 -5.517896 90)
			(unlocked yes)
			(layer "F.Fab")
			(hide yes)
			(effects
				(font
					(size 1.016 1.016)
					(thickness 0.1524)
				)
			)
		)
		(duplicate_pad_numbers_are_jumpers no)
		(fp_line
			(start 0.508 -0.9398)
			(end -0.508 -0.9398)
			(stroke
				(width 0.1524)
				(type default)
			)
			(layer "F.SilkS")
		)
		(fp_line
			(start -0.508 -0.9398)
			(end -0.508 0.9398)
			(stroke
				(width 0.1524)
				(type default)
			)
			(layer "F.SilkS")
		)
		(fp_rect
			(start -0.508 0.9398)
			(end 0.508 -0.9398)
			(stroke
				(width 0)
				(type default)
			)
			(fill no)
			(layer "F.CrtYd")
		)
		(fp_rect
			(start -0.508 0.9398)
			(end 0.508 -0.9398)
			(stroke
				(width 0)
				(type default)
			)
			(fill no)
			(layer "F.Fab")
		)
		(pad "1" smd custom
			(at 0 -0.4445 90)
			(size 0.1397 0.1397)
			(layers "F.Cu" "F.Mask" "F.Paste")
			(net "GND")
			(options
				(clearance outline)
				(anchor circle)
			)
			(primitives
				(gr_poly
					(pts
						(arc
							(start -0.1778 -0.2794)
							(mid -0.249642 -0.249642)
							(end -0.2794 -0.1778)
						)
						(arc
							(start -0.2794 0.1778)
							(mid -0.249642 0.249642)
							(end -0.1778 0.2794)
						)
						(arc
							(start 0.1778 0.2794)
							(mid 0.249642 0.249642)
							(end 0.2794 0.1778)
						)
						(arc
							(start 0.2794 -0.1778)
							(mid 0.249642 -0.249642)
							(end 0.1778 -0.2794)
						)
					)
					(width 0)
					(fill yes)
				)
			)
		)
		(pad "2" smd custom
			(at 0 0.4445 90)
			(size 0.1397 0.1397)
			(layers "F.Cu" "F.Mask" "F.Paste")
			(net "IOM_TYPE3")
			(options
				(clearance outline)
				(anchor circle)
			)
			(primitives
				(gr_poly
					(pts
						(arc
							(start -0.1778 -0.2794)
							(mid -0.249642 -0.249642)
							(end -0.2794 -0.1778)
						)
						(arc
							(start -0.2794 0.1778)
							(mid -0.249642 0.249642)
							(end -0.1778 0.2794)
						)
						(arc
							(start 0.1778 0.2794)
							(mid 0.249642 0.249642)
							(end 0.2794 0.1778)
						)
						(arc
							(start 0.2794 -0.1778)
							(mid 0.249642 -0.249642)
							(end 0.1778 -0.2794)
						)
					)
					(width 0)
					(fill yes)
				)
			)
		)
	)
	(footprint ""
		(layer "F.Cu")
		(at 207.323436 -98.984308 -90)
		(property "Reference" "C323"
			(at 0 0 270)
			(layer "F.SilkS")
			(hide yes)
			(effects
				(font
					(size 1.27 1.27)
				)
			)
		)
		(property "Value" "SCD1U16V2KX-3GP"
			(at 1.1811 -2.7051 270)
			(unlocked yes)
			(layer "F.Fab")
			(hide yes)
			(effects
				(font
					(size 1.016 1.016)
					(thickness 0.1524)
				)
			)
		)
		(property "Device Type" "C402H22"
			(at 1.1811 -4.2291 270)
			(unlocked yes)
			(layer "F.Fab")
			(hide yes)
			(effects
				(font
					(size 1.016 1.016)
					(thickness 0.1524)
				)
			)
		)
		(duplicate_pad_numbers_are_jumpers no)
		(fp_rect
			(start -0.4318 0.9525)
			(end 0.4318 -0.9525)
			(stroke
				(width 0)
				(type default)
			)
			(fill no)
			(layer "F.CrtYd")
		)
		(fp_rect
			(start -0.4318 0.9525)
			(end 0.4318 -0.9525)
			(stroke
				(width 0)
				(type default)
			)
			(fill no)
			(layer "F.Fab")
		)
		(pad "1" smd custom
			(at 0 -0.4445 270)
			(size 0.1524 0.1524)
			(layers "F.Cu" "F.Mask" "F.Paste")
			(net "P1V8")
			(options
				(clearance outline)
				(anchor circle)
			)
			(primitives
				(gr_poly
					(pts
						(arc
							(start 0.3048 -0.2032)
							(mid 0.275042 -0.275042)
							(end 0.2032 -0.3048)
						)
						(arc
							(start -0.2032 -0.3048)
							(mid -0.275042 -0.275042)
							(end -0.3048 -0.2032)
						)
						(arc
							(start -0.3048 0.2032)
							(mid -0.275042 0.275042)
							(end -0.2032 0.3048)
						)
						(arc
							(start 0.2032 0.3048)
							(mid 0.275042 0.275042)
							(end 0.3048 0.2032)
						)
					)
					(width 0)
					(fill yes)
				)
			)
		)
		(pad "2" smd custom
			(at 0 0.4445 270)
			(size 0.1524 0.1524)
			(layers "F.Cu" "F.Mask" "F.Paste")
			(net "GND")
			(options
				(clearance outline)
				(anchor circle)
			)
			(primitives
				(gr_poly
					(pts
						(arc
							(start 0.3048 -0.2032)
							(mid 0.275042 -0.275042)
							(end 0.2032 -0.3048)
						)
						(arc
							(start -0.2032 -0.3048)
							(mid -0.275042 -0.275042)
							(end -0.3048 -0.2032)
						)
						(arc
							(start -0.3048 0.2032)
							(mid -0.275042 0.275042)
							(end -0.2032 0.3048)
						)
						(arc
							(start 0.2032 0.3048)
							(mid 0.275042 0.275042)
							(end 0.3048 0.2032)
						)
					)
					(width 0)
					(fill yes)
				)
			)
		)
	)
	(footprint ""
		(layer "F.Cu")
		(at 176.0982 -75.438)
		(property "Reference" "TP121"
			(at 0 0 0)
			(layer "F.SilkS")
			(hide yes)
			(effects
				(font
					(size 1.27 1.27)
				)
			)
		)
		(property "Value" "TPAD28-2-GP"
			(at -0.0127 -1.6637 0)
			(unlocked yes)
			(layer "F.Fab")
			(hide yes)
			(effects
				(font
					(size 1.016 1.016)
					(thickness 0.1524)
				)
			)
		)
		(property "Device Type" "TPAD28"
			(at -0.0127 -3.1877 0)
			(unlocked yes)
			(layer "F.Fab")
			(hide yes)
			(effects
				(font
					(size 1.016 1.016)
					(thickness 0.1524)
				)
			)
		)
		(duplicate_pad_numbers_are_jumpers no)
		(fp_poly
			(pts
				(arc
					(start 0.3556 0)
					(mid -0.3556 0)
					(end 0.3556 0)
				)
			)
			(stroke
				(width 0)
				(type default)
			)
			(fill no)
			(layer "F.CrtYd")
		)
		(fp_poly
			(pts
				(arc
					(start 0.6096 0)
					(mid -0.6096 0)
					(end 0.6096 0)
				)
			)
			(stroke
				(width 0)
				(type default)
			)
			(fill no)
			(layer "F.Fab")
		)
		(pad "1" smd circle
			(at 0 0)
			(size 0.7112 0.7112)
			(layers "F.Cu" "F.Mask" "F.Paste")
			(net "IOC_GPIO_31")
		)
	)
	(footprint ""
		(layer "F.Cu")
		(at 195.453 -19.177)
		(property "Reference" "U49"
			(at 0 0 0)
			(layer "F.SilkS")
			(hide yes)
			(effects
				(font
					(size 1.27 1.27)
				)
			)
		)
		(property "Value" "SN74LVC1G08DCKR-GP"
			(at -2.3368 -8.6868 0)
			(unlocked yes)
			(layer "F.Fab")
			(hide yes)
			(effects
				(font
					(size 1.016 1.016)
					(thickness 0.1524)
				)
			)
		)
		(property "Device Type" "SC70-5H44"
			(at -2.3114 -10.414 0)
			(unlocked yes)
			(layer "F.Fab")
			(hide yes)
			(effects
				(font
					(size 1.016 1.016)
					(thickness 0.1524)
				)
			)
		)
		(duplicate_pad_numbers_are_jumpers no)
		(fp_line
			(start -1.27 -1.7018)
			(end 1.27 -1.7018)
			(stroke
				(width 0.1524)
				(type default)
			)
			(layer "F.SilkS")
		)
		(fp_line
			(start -1.27 1.7018)
			(end -1.27 -1.7018)
			(stroke
				(width 0.1524)
				(type default)
			)
			(layer "F.SilkS")
		)
		(fp_line
			(start 0.6604 -1.8034)
			(end 1.3843 -1.8034)
			(stroke
				(width 0.3302)
				(type default)
			)
			(layer "F.SilkS")
		)
		(fp_line
			(start 1.27 -1.7018)
			(end 1.27 1.7018)
			(stroke
				(width 0.1524)
				(type default)
			)
			(layer "F.SilkS")
		)
		(fp_line
			(start 1.27 1.7018)
			(end -1.27 1.7018)
			(stroke
				(width 0.1524)
				(type default)
			)
			(layer "F.SilkS")
		)
		(fp_line
			(start 1.3843 -1.8034)
			(end 1.3843 -1.1176)
			(stroke
				(width 0.3302)
				(type default)
			)
			(layer "F.SilkS")
		)
		(fp_rect
			(start -1.524 1.9558)
			(end 1.524 -1.9558)
			(stroke
				(width 0)
				(type default)
			)
			(fill no)
			(layer "F.CrtYd")
		)
		(fp_poly
			(pts
				(xy -1.524 -1.9558) (xy 1.524 -1.9558) (xy 1.524 1.9558) (xy -1.524 1.9558)
			)
			(stroke
				(width 0)
				(type default)
			)
			(fill no)
			(layer "F.Fab")
		)
		(pad "1" smd rect
			(at 0.65024 -0.8255)
			(size 0.4064 1.2192)
			(layers "F.Cu" "F.Mask" "F.Paste")
			(net "BMC_EXT1_LED_Y")
		)
		(pad "2" smd rect
			(at 0 -0.8255)
			(size 0.4064 1.2192)
			(layers "F.Cu" "F.Mask" "F.Paste")
			(net "EXT1_LED_YELLOW_D")
		)
		(pad "3" smd rect
			(at -0.65024 -0.8255)
			(size 0.4064 1.2192)
			(layers "F.Cu" "F.Mask" "F.Paste")
			(net "GND")
		)
		(pad "4" smd rect
			(at -0.65024 0.8255)
			(size 0.4064 1.2192)
			(layers "F.Cu" "F.Mask" "F.Paste")
			(net "EXT1_LED_YELLOW_G1")
		)
		(pad "5" smd rect
			(at 0.65024 0.8255)
			(size 0.4064 1.2192)
			(layers "F.Cu" "F.Mask" "F.Paste")
			(net "P3V3_STBY")
		)
	)
	(footprint ""
		(layer "F.Cu")
		(at 42.9006 -161.3662)
		(property "Reference" "R313"
			(at 0 0 0)
			(layer "F.SilkS")
			(hide yes)
			(effects
				(font
					(size 1.27 1.27)
				)
			)
		)
		(property "Value" "4K7R2F-GP"
			(at 0.064008 -3.993896 0)
			(unlocked yes)
			(layer "F.Fab")
			(hide yes)
			(effects
				(font
					(size 1.016 1.016)
					(thickness 0.1524)
				)
			)
		)
		(property "Device Type" "R402H16"
			(at 0.064008 -5.517896 0)
			(unlocked yes)
			(layer "F.Fab")
			(hide yes)
			(effects
				(font
					(size 1.016 1.016)
					(thickness 0.1524)
				)
			)
		)
		(duplicate_pad_numbers_are_jumpers no)
		(fp_line
			(start -0.508 -0.9398)
			(end -0.508 0.9398)
			(stroke
				(width 0.1524)
				(type default)
			)
			(layer "F.SilkS")
		)
		(fp_line
			(start 0.508 -0.9398)
			(end -0.508 -0.9398)
			(stroke
				(width 0.1524)
				(type default)
			)
			(layer "F.SilkS")
		)
		(fp_rect
			(start -0.508 0.9398)
			(end 0.508 -0.9398)
			(stroke
				(width 0)
				(type default)
			)
			(fill no)
			(layer "F.CrtYd")
		)
		(fp_rect
			(start -0.508 0.9398)
			(end 0.508 -0.9398)
			(stroke
				(width 0)
				(type default)
			)
			(fill no)
			(layer "F.Fab")
		)
		(pad "1" smd custom
			(at 0 -0.4445)
			(size 0.1397 0.1397)
			(layers "F.Cu" "F.Mask" "F.Paste")
			(net "GND")
			(options
				(clearance outline)
				(anchor circle)
			)
			(primitives
				(gr_poly
					(pts
						(arc
							(start -0.1778 -0.2794)
							(mid -0.249642 -0.249642)
							(end -0.2794 -0.1778)
						)
						(arc
							(start -0.2794 0.1778)
							(mid -0.249642 0.249642)
							(end -0.1778 0.2794)
						)
						(arc
							(start 0.1778 0.2794)
							(mid 0.249642 0.249642)
							(end 0.2794 0.1778)
						)
						(arc
							(start 0.2794 -0.1778)
							(mid 0.249642 -0.249642)
							(end 0.1778 -0.2794)
						)
					)
					(width 0)
					(fill yes)
				)
			)
		)
		(pad "2" smd custom
			(at 0 0.4445)
			(size 0.1397 0.1397)
			(layers "F.Cu" "F.Mask" "F.Paste")
			(net "BOARD_REV_0")
			(options
				(clearance outline)
				(anchor circle)
			)
			(primitives
				(gr_poly
					(pts
						(arc
							(start -0.1778 -0.2794)
							(mid -0.249642 -0.249642)
							(end -0.2794 -0.1778)
						)
						(arc
							(start -0.2794 0.1778)
							(mid -0.249642 0.249642)
							(end -0.1778 0.2794)
						)
						(arc
							(start 0.1778 0.2794)
							(mid 0.249642 0.249642)
							(end 0.2794 0.1778)
						)
						(arc
							(start 0.2794 -0.1778)
							(mid 0.249642 -0.249642)
							(end 0.1778 -0.2794)
						)
					)
					(width 0)
					(fill yes)
				)
			)
		)
	)
)
